(kicad_pcb
	(version 20260206)
	(generator "pcbnew")
	(generator_version "10.0")
	(general
		(thickness 1.6)
		(legacy_teardrops no)
	)
	(paper "A4")
	(title_block
		(title "04192023_DAF0TMB3IC0_F0TG_MB_C_brd_V02_OCP.brd")
		(comment 1 "Grand Teton / footprints 6987-6991 of 8354")
	)
	(layers
		(0 "F.Cu" signal "TOP")
		(4 "In1.Cu" signal "GND")
		(6 "In2.Cu" signal "IN1")
		(8 "In3.Cu" signal "GND1")
		(10 "In4.Cu" signal "IN2")
		(12 "In5.Cu" signal "GND2")
		(14 "In6.Cu" signal "IN3")
		(16 "In7.Cu" signal "GND3")
		(18 "In8.Cu" signal "VCC")
		(20 "In9.Cu" signal "VCC1")
		(22 "In10.Cu" signal "GND4")
		(24 "In11.Cu" signal "IN4")
		(26 "In12.Cu" signal "GND5")
		(28 "In13.Cu" signal "IN5")
		(30 "In14.Cu" signal "GND6")
		(32 "In15.Cu" signal "IN6")
		(34 "In16.Cu" signal "GND7")
		(2 "B.Cu" signal "BOTTOM")
		(9 "F.Adhes" user "F.Adhesive")
		(11 "B.Adhes" user "B.Adhesive")
		(13 "F.Paste" user "Package Geometry/Pastemask Top")
		(15 "B.Paste" user "Package Geometry/Pastemask Bottom")
		(5 "F.SilkS" user "Ref Des/Silkscreen Top")
		(7 "B.SilkS" user "Ref Des/Silkscreen Bottom")
		(1 "F.Mask" user "Board Geometry/Soldermask Top")
		(3 "B.Mask" user "Board Geometry/Soldermask Bottom")
		(17 "Dwgs.User" user "User.Drawings")
		(19 "Cmts.User" user "User.Comments")
		(21 "Eco1.User" user "User.Eco1")
		(23 "Eco2.User" user "User.Eco2")
		(25 "Edge.Cuts" user "Board Geometry/Outline")
		(27 "Margin" user)
		(31 "F.CrtYd" user "Package Geometry/Place Bound Top")
		(29 "B.CrtYd" user "Package Geometry/Place Bound Bottom")
		(35 "F.Fab" user "Ref Des/Assembly Top")
		(33 "B.Fab" user "Ref Des/Assembly Bottom")
	)
	(footprint ""
		(layer "B.Cu")
		(at 228.485192 -326.49668 180)
		(property "Reference" "C1091"
			(at 0 0 0)
			(layer "B.SilkS")
			(hide yes)
			(effects
				(font
					(size 1.27 1.27)
				)
				(justify mirror)
			)
		)
		(property "Value" ""
			(at 0 0 0)
			(layer "B.Fab")
			(effects
				(font
					(size 1.27 1.27)
				)
				(justify mirror)
			)
		)
		(duplicate_pad_numbers_are_jumpers no)
		(fp_line
			(start 0.7874 0.4064)
			(end 0.7874 -0.4064)
			(stroke
				(width 0.1524)
				(type default)
			)
			(layer "B.SilkS")
		)
		(fp_line
			(start 0.7874 -0.4064)
			(end -0.7874 -0.4064)
			(stroke
				(width 0.1524)
				(type default)
			)
			(layer "B.SilkS")
		)
		(fp_line
			(start -0.7874 0.4064)
			(end 0.7874 0.4064)
			(stroke
				(width 0.1524)
				(type default)
			)
			(layer "B.SilkS")
		)
		(fp_line
			(start -0.7874 -0.4064)
			(end -0.7874 0.4064)
			(stroke
				(width 0.1524)
				(type default)
			)
			(layer "B.SilkS")
		)
		(fp_line
			(start 0.67945 0.3048)
			(end 0.67945 -0.305054)
			(stroke
				(width 0.1)
				(type default)
			)
			(layer "B.Fab")
		)
		(fp_line
			(start 0.67945 -0.305054)
			(end 0.12065 -0.305054)
			(stroke
				(width 0.1)
				(type default)
			)
			(layer "B.Fab")
		)
		(fp_line
			(start 0.12065 0.3048)
			(end 0.67945 0.3048)
			(stroke
				(width 0.1)
				(type default)
			)
			(layer "B.Fab")
		)
		(fp_line
			(start 0.12065 0.2794)
			(end 0.12065 0.3048)
			(stroke
				(width 0.1)
				(type default)
			)
			(layer "B.Fab")
		)
		(fp_line
			(start 0.12065 -0.2794)
			(end -0.12065 -0.2794)
			(stroke
				(width 0.1)
				(type default)
			)
			(layer "B.Fab")
		)
		(fp_line
			(start 0.12065 -0.305054)
			(end 0.12065 -0.2794)
			(stroke
				(width 0.1)
				(type default)
			)
			(layer "B.Fab")
		)
		(fp_line
			(start -0.120396 0.3048)
			(end -0.120396 0.2794)
			(stroke
				(width 0.1)
				(type default)
			)
			(layer "B.Fab")
		)
		(fp_line
			(start -0.120396 0.2794)
			(end 0.12065 0.2794)
			(stroke
				(width 0.1)
				(type default)
			)
			(layer "B.Fab")
		)
		(fp_line
			(start -0.12065 -0.2794)
			(end -0.12065 -0.3048)
			(stroke
				(width 0.1)
				(type default)
			)
			(layer "B.Fab")
		)
		(fp_line
			(start -0.12065 -0.3048)
			(end -0.67945 -0.3048)
			(stroke
				(width 0.1)
				(type default)
			)
			(layer "B.Fab")
		)
		(fp_line
			(start -0.67945 0.3048)
			(end -0.120396 0.3048)
			(stroke
				(width 0.1)
				(type default)
			)
			(layer "B.Fab")
		)
		(fp_line
			(start -0.67945 -0.3048)
			(end -0.67945 0.3048)
			(stroke
				(width 0.1)
				(type default)
			)
			(layer "B.Fab")
		)
		(pad "1" smd circle
			(at 0.40005 0)
			(size 0 0)
			(layers "B.Cu" "B.Mask" "B.Paste")
			(net "P1V8_CPU1_RT_1D_ADC_TIC")
		)
		(pad "2" smd circle
			(at -0.40005 0)
			(size 0 0)
			(layers "B.Cu" "B.Mask" "B.Paste")
			(net "GND")
		)
	)
	(footprint ""
		(layer "B.Cu")
		(at 11.049 -81.153 90)
		(property "Reference" "R8013"
			(at 0 0 90)
			(layer "B.SilkS")
			(hide yes)
			(effects
				(font
					(size 1.27 1.27)
				)
				(justify mirror)
			)
		)
		(property "Value" ""
			(at 0 0 90)
			(layer "B.Fab")
			(effects
				(font
					(size 1.27 1.27)
				)
				(justify mirror)
			)
		)
		(duplicate_pad_numbers_are_jumpers no)
		(fp_line
			(start 0.7874 -0.4064)
			(end -0.7874 -0.4064)
			(stroke
				(width 0.1524)
				(type default)
			)
			(layer "B.SilkS")
		)
		(fp_line
			(start -0.7874 -0.4064)
			(end -0.7874 0.4064)
			(stroke
				(width 0.1524)
				(type default)
			)
			(layer "B.SilkS")
		)
		(fp_line
			(start 0.7874 0.4064)
			(end 0.7874 -0.4064)
			(stroke
				(width 0.1524)
				(type default)
			)
			(layer "B.SilkS")
		)
		(fp_line
			(start -0.7874 0.4064)
			(end 0.7874 0.4064)
			(stroke
				(width 0.1524)
				(type default)
			)
			(layer "B.SilkS")
		)
		(fp_line
			(start 0.67945 -0.305054)
			(end 0.12065 -0.305054)
			(stroke
				(width 0.1)
				(type default)
			)
			(layer "B.Fab")
		)
		(fp_line
			(start 0.12065 -0.305054)
			(end 0.12065 -0.2794)
			(stroke
				(width 0.1)
				(type default)
			)
			(layer "B.Fab")
		)
		(fp_line
			(start -0.12065 -0.3048)
			(end -0.67945 -0.3048)
			(stroke
				(width 0.1)
				(type default)
			)
			(layer "B.Fab")
		)
		(fp_line
			(start -0.67945 -0.3048)
			(end -0.67945 0.3048)
			(stroke
				(width 0.1)
				(type default)
			)
			(layer "B.Fab")
		)
		(fp_line
			(start 0.12065 -0.2794)
			(end -0.12065 -0.2794)
			(stroke
				(width 0.1)
				(type default)
			)
			(layer "B.Fab")
		)
		(fp_line
			(start -0.12065 -0.2794)
			(end -0.12065 -0.3048)
			(stroke
				(width 0.1)
				(type default)
			)
			(layer "B.Fab")
		)
		(fp_line
			(start 0.12065 0.2794)
			(end 0.12065 0.3048)
			(stroke
				(width 0.1)
				(type default)
			)
			(layer "B.Fab")
		)
		(fp_line
			(start -0.120396 0.2794)
			(end 0.12065 0.2794)
			(stroke
				(width 0.1)
				(type default)
			)
			(layer "B.Fab")
		)
		(fp_line
			(start 0.67945 0.3048)
			(end 0.67945 -0.305054)
			(stroke
				(width 0.1)
				(type default)
			)
			(layer "B.Fab")
		)
		(fp_line
			(start 0.12065 0.3048)
			(end 0.67945 0.3048)
			(stroke
				(width 0.1)
				(type default)
			)
			(layer "B.Fab")
		)
		(fp_line
			(start -0.120396 0.3048)
			(end -0.120396 0.2794)
			(stroke
				(width 0.1)
				(type default)
			)
			(layer "B.Fab")
		)
		(fp_line
			(start -0.67945 0.3048)
			(end -0.120396 0.3048)
			(stroke
				(width 0.1)
				(type default)
			)
			(layer "B.Fab")
		)
		(pad "1" smd circle
			(at 0.40005 0 270)
			(size 0 0)
			(layers "B.Cu" "B.Mask" "B.Paste")
			(net "OCP_SFF_PRSNT01_R_N")
		)
		(pad "2" smd circle
			(at -0.40005 0 270)
			(size 0 0)
			(layers "B.Cu" "B.Mask" "B.Paste")
			(net "OCP_SFF_PRSNT01_R1_N")
		)
	)
	(footprint ""
		(layer "B.Cu")
		(at 79.918814 -390.560052 90)
		(property "Reference" "C332"
			(at 0 0 90)
			(layer "B.SilkS")
			(hide yes)
			(effects
				(font
					(size 1.27 1.27)
				)
				(justify mirror)
			)
		)
		(property "Value" ""
			(at 0 0 90)
			(layer "B.Fab")
			(effects
				(font
					(size 1.27 1.27)
				)
				(justify mirror)
			)
		)
		(duplicate_pad_numbers_are_jumpers no)
		(fp_line
			(start 0.7874 -0.4064)
			(end -0.7874 -0.4064)
			(stroke
				(width 0.1524)
				(type default)
			)
			(layer "B.SilkS")
		)
		(fp_line
			(start -0.7874 -0.4064)
			(end -0.7874 0.4064)
			(stroke
				(width 0.1524)
				(type default)
			)
			(layer "B.SilkS")
		)
		(fp_line
			(start 0.7874 0.4064)
			(end 0.7874 -0.4064)
			(stroke
				(width 0.1524)
				(type default)
			)
			(layer "B.SilkS")
		)
		(fp_line
			(start -0.7874 0.4064)
			(end 0.7874 0.4064)
			(stroke
				(width 0.1524)
				(type default)
			)
			(layer "B.SilkS")
		)
		(fp_line
			(start 0.67945 -0.305054)
			(end 0.12065 -0.305054)
			(stroke
				(width 0.1)
				(type default)
			)
			(layer "B.Fab")
		)
		(fp_line
			(start 0.12065 -0.305054)
			(end 0.12065 -0.2794)
			(stroke
				(width 0.1)
				(type default)
			)
			(layer "B.Fab")
		)
		(fp_line
			(start -0.12065 -0.3048)
			(end -0.67945 -0.3048)
			(stroke
				(width 0.1)
				(type default)
			)
			(layer "B.Fab")
		)
		(fp_line
			(start -0.67945 -0.3048)
			(end -0.67945 0.3048)
			(stroke
				(width 0.1)
				(type default)
			)
			(layer "B.Fab")
		)
		(fp_line
			(start 0.12065 -0.2794)
			(end -0.12065 -0.2794)
			(stroke
				(width 0.1)
				(type default)
			)
			(layer "B.Fab")
		)
		(fp_line
			(start -0.12065 -0.2794)
			(end -0.12065 -0.3048)
			(stroke
				(width 0.1)
				(type default)
			)
			(layer "B.Fab")
		)
		(fp_line
			(start 0.12065 0.2794)
			(end 0.12065 0.3048)
			(stroke
				(width 0.1)
				(type default)
			)
			(layer "B.Fab")
		)
		(fp_line
			(start -0.120396 0.2794)
			(end 0.12065 0.2794)
			(stroke
				(width 0.1)
				(type default)
			)
			(layer "B.Fab")
		)
		(fp_line
			(start 0.67945 0.3048)
			(end 0.67945 -0.305054)
			(stroke
				(width 0.1)
				(type default)
			)
			(layer "B.Fab")
		)
		(fp_line
			(start 0.12065 0.3048)
			(end 0.67945 0.3048)
			(stroke
				(width 0.1)
				(type default)
			)
			(layer "B.Fab")
		)
		(fp_line
			(start -0.120396 0.3048)
			(end -0.120396 0.2794)
			(stroke
				(width 0.1)
				(type default)
			)
			(layer "B.Fab")
		)
		(fp_line
			(start -0.67945 0.3048)
			(end -0.120396 0.3048)
			(stroke
				(width 0.1)
				(type default)
			)
			(layer "B.Fab")
		)
		(pad "1" smd circle
			(at 0.40005 0 270)
			(size 0 0)
			(layers "B.Cu" "B.Mask" "B.Paste")
			(net "P0V9_CPU1_RT1_2A")
		)
		(pad "2" smd circle
			(at -0.40005 0 270)
			(size 0 0)
			(layers "B.Cu" "B.Mask" "B.Paste")
			(net "GND")
		)
	)
	(footprint ""
		(layer "B.Cu")
		(at 108.089192 -29.55544 -90)
		(property "Reference" "C6099"
			(at 0 0 90)
			(layer "B.SilkS")
			(hide yes)
			(effects
				(font
					(size 1.27 1.27)
				)
				(justify mirror)
			)
		)
		(property "Value" ""
			(at 0 0 90)
			(layer "B.Fab")
			(effects
				(font
					(size 1.27 1.27)
				)
				(justify mirror)
			)
		)
		(duplicate_pad_numbers_are_jumpers no)
		(fp_line
			(start -0.7874 0.4064)
			(end 0.7874 0.4064)
			(stroke
				(width 0.1524)
				(type default)
			)
			(layer "B.SilkS")
		)
		(fp_line
			(start 0.7874 0.4064)
			(end 0.7874 -0.4064)
			(stroke
				(width 0.1524)
				(type default)
			)
			(layer "B.SilkS")
		)
		(fp_line
			(start -0.7874 -0.4064)
			(end -0.7874 0.4064)
			(stroke
				(width 0.1524)
				(type default)
			)
			(layer "B.SilkS")
		)
		(fp_line
			(start 0.7874 -0.4064)
			(end -0.7874 -0.4064)
			(stroke
				(width 0.1524)
				(type default)
			)
			(layer "B.SilkS")
		)
		(fp_line
			(start -0.67945 0.3048)
			(end -0.120396 0.3048)
			(stroke
				(width 0.1)
				(type default)
			)
			(layer "B.Fab")
		)
		(fp_line
			(start -0.120396 0.3048)
			(end -0.120396 0.2794)
			(stroke
				(width 0.1)
				(type default)
			)
			(layer "B.Fab")
		)
		(fp_line
			(start 0.12065 0.3048)
			(end 0.67945 0.3048)
			(stroke
				(width 0.1)
				(type default)
			)
			(layer "B.Fab")
		)
		(fp_line
			(start 0.67945 0.3048)
			(end 0.67945 -0.305054)
			(stroke
				(width 0.1)
				(type default)
			)
			(layer "B.Fab")
		)
		(fp_line
			(start -0.120396 0.2794)
			(end 0.12065 0.2794)
			(stroke
				(width 0.1)
				(type default)
			)
			(layer "B.Fab")
		)
		(fp_line
			(start 0.12065 0.2794)
			(end 0.12065 0.3048)
			(stroke
				(width 0.1)
				(type default)
			)
			(layer "B.Fab")
		)
		(fp_line
			(start -0.12065 -0.2794)
			(end -0.12065 -0.3048)
			(stroke
				(width 0.1)
				(type default)
			)
			(layer "B.Fab")
		)
		(fp_line
			(start 0.12065 -0.2794)
			(end -0.12065 -0.2794)
			(stroke
				(width 0.1)
				(type default)
			)
			(layer "B.Fab")
		)
		(fp_line
			(start -0.67945 -0.3048)
			(end -0.67945 0.3048)
			(stroke
				(width 0.1)
				(type default)
			)
			(layer "B.Fab")
		)
		(fp_line
			(start -0.12065 -0.3048)
			(end -0.67945 -0.3048)
			(stroke
				(width 0.1)
				(type default)
			)
			(layer "B.Fab")
		)
		(fp_line
			(start 0.12065 -0.305054)
			(end 0.12065 -0.2794)
			(stroke
				(width 0.1)
				(type default)
			)
			(layer "B.Fab")
		)
		(fp_line
			(start 0.67945 -0.305054)
			(end 0.12065 -0.305054)
			(stroke
				(width 0.1)
				(type default)
			)
			(layer "B.Fab")
		)
		(pad "1" smd circle
			(at 0.40005 0 90)
			(size 0 0)
			(layers "B.Cu" "B.Mask" "B.Paste")
			(net "P3V3_AUX_CPU0_USB2_AVDD33")
		)
		(pad "2" smd circle
			(at -0.40005 0 90)
			(size 0 0)
			(layers "B.Cu" "B.Mask" "B.Paste")
			(net "GND")
		)
	)
	(footprint ""
		(layer "B.Cu")
		(at 181.182518 -412.949644 90)
		(property "Reference" "R2820"
			(at 0 0 90)
			(layer "B.SilkS")
			(hide yes)
			(effects
				(font
					(size 1.27 1.27)
				)
				(justify mirror)
			)
		)
		(property "Value" ""
			(at 0 0 90)
			(layer "B.Fab")
			(effects
				(font
					(size 1.27 1.27)
				)
				(justify mirror)
			)
		)
		(duplicate_pad_numbers_are_jumpers no)
		(fp_line
			(start 0.7874 -0.4064)
			(end -0.7874 -0.4064)
			(stroke
				(width 0.1524)
				(type default)
			)
			(layer "B.SilkS")
		)
		(fp_line
			(start -0.7874 -0.4064)
			(end -0.7874 0.4064)
			(stroke
				(width 0.1524)
				(type default)
			)
			(layer "B.SilkS")
		)
		(fp_line
			(start 0.7874 0.4064)
			(end 0.7874 -0.4064)
			(stroke
				(width 0.1524)
				(type default)
			)
			(layer "B.SilkS")
		)
		(fp_line
			(start -0.7874 0.4064)
			(end 0.7874 0.4064)
			(stroke
				(width 0.1524)
				(type default)
			)
			(layer "B.SilkS")
		)
		(fp_line
			(start 0.67945 -0.305054)
			(end 0.12065 -0.305054)
			(stroke
				(width 0.1)
				(type default)
			)
			(layer "B.Fab")
		)
		(fp_line
			(start 0.12065 -0.305054)
			(end 0.12065 -0.2794)
			(stroke
				(width 0.1)
				(type default)
			)
			(layer "B.Fab")
		)
		(fp_line
			(start -0.12065 -0.3048)
			(end -0.67945 -0.3048)
			(stroke
				(width 0.1)
				(type default)
			)
			(layer "B.Fab")
		)
		(fp_line
			(start -0.67945 -0.3048)
			(end -0.67945 0.3048)
			(stroke
				(width 0.1)
				(type default)
			)
			(layer "B.Fab")
		)
		(fp_line
			(start 0.12065 -0.2794)
			(end -0.12065 -0.2794)
			(stroke
				(width 0.1)
				(type default)
			)
			(layer "B.Fab")
		)
		(fp_line
			(start -0.12065 -0.2794)
			(end -0.12065 -0.3048)
			(stroke
				(width 0.1)
				(type default)
			)
			(layer "B.Fab")
		)
		(fp_line
			(start 0.12065 0.2794)
			(end 0.12065 0.3048)
			(stroke
				(width 0.1)
				(type default)
			)
			(layer "B.Fab")
		)
		(fp_line
			(start -0.120396 0.2794)
			(end 0.12065 0.2794)
			(stroke
				(width 0.1)
				(type default)
			)
			(layer "B.Fab")
		)
		(fp_line
			(start 0.67945 0.3048)
			(end 0.67945 -0.305054)
			(stroke
				(width 0.1)
				(type default)
			)
			(layer "B.Fab")
		)
		(fp_line
			(start 0.12065 0.3048)
			(end 0.67945 0.3048)
			(stroke
				(width 0.1)
				(type default)
			)
			(layer "B.Fab")
		)
		(fp_line
			(start -0.120396 0.3048)
			(end -0.120396 0.2794)
			(stroke
				(width 0.1)
				(type default)
			)
			(layer "B.Fab")
		)
		(fp_line
			(start -0.67945 0.3048)
			(end -0.120396 0.3048)
			(stroke
				(width 0.1)
				(type default)
			)
			(layer "B.Fab")
		)
		(pad "1" smd circle
			(at 0.40005 0 270)
			(size 0 0)
			(layers "B.Cu" "B.Mask" "B.Paste")
			(net "P3V3_AUX")
		)
		(pad "2" smd circle
			(at -0.40005 0 270)
			(size 0 0)
			(layers "B.Cu" "B.Mask" "B.Paste")
			(net "BMC_MONITER_BUF_R")
		)
	)
)
